#ISCELL
  mstr_misc dns *
  *
#ISCELL
  pure_quanta quanta_title_block_c *
  *
#ISCELL
  pure_quanta_power cad_note *
  *
#ISCELL
  pure_quanta_power universal_gnd *
  page341_i1
#CELL
  pure_quanta q_res *
  page341_i10
#ISCELL
  pure_quanta_power universal_gnd *
  page341_i100
#ISCELL
  standard tap *
  page341_i101
#ISCELL
  pure_quanta_power universal_power *
  page341_i102
#ISCELL
  standard tap *
  page341_i103
#ISCELL
  standard tap *
  page341_i104
#ISCELL
  standard tap *
  page341_i105
#ISCELL
  standard tap *
  page341_i106
#ISCELL
  standard tap *
  page341_i107
#ISCELL
  standard tap *
  page341_i108
#ISCELL
  standard tap *
  page341_i109
#CELL
  pure_quanta q_res *
  page341_i11
#ISCELL
  standard tap *
  page341_i110
#ISCELL
  standard tap *
  page341_i111
#ISCELL
  standard tap *
  page341_i112
#ISCELL
  standard tap *
  page341_i113
#ISCELL
  standard tap *
  page341_i114
#ISCELL
  standard tap *
  page341_i115
#ISCELL
  standard tap *
  page341_i116
#ISCELL
  standard tap *
  page341_i117
#ISCELL
  standard tap *
  page341_i118
#ISCELL
  standard tap *
  page341_i119
#CELL
  pure_quanta q_res *
  page341_i12
#ISCELL
  standard tap *
  page341_i120
#ISCELL
  standard tap *
  page341_i121
#ISCELL
  standard tap *
  page341_i122
#ISCELL
  standard tap *
  page341_i123
#ISCELL
  standard tap *
  page341_i124
#ISCELL
  standard tap *
  page341_i125
#ISCELL
  standard tap *
  page341_i126
#ISCELL
  standard tap *
  page341_i127
#ISCELL
  standard tap *
  page341_i128
#ISCELL
  standard tap *
  page341_i129
#CELL
  pure_quanta q_cap *
  page341_i13
#ISCELL
  standard tap *
  page341_i130
#ISCELL
  standard tap *
  page341_i131
#ISCELL
  standard tap *
  page341_i132
#ISCELL
  standard tap *
  page341_i133
#ISCELL
  standard offpage *
  page341_i134
#CELL
  pure_quanta q_res *
  page341_i135
#CELL
  pure_quanta q_res *
  page341_i136
#ISCELL
  pure_quanta_power universal_power *
  page341_i137
#ISCELL
  standard offpage *
  page341_i138
#CELL
  pure_quanta q_cap *
  page341_i14
#ISCELL
  standard offpage *
  page341_i141
#ISCELL
  standard offpage *
  page341_i142
#ISCELL
  standard offpage *
  page341_i143
#ISCELL
  standard offpage *
  page341_i144
#ISCELL
  standard offpage *
  page341_i145
#ISCELL
  standard offpage *
  page341_i146
#ISCELL
  standard offpage *
  page341_i147
#ISCELL
  standard offpage *
  page341_i148
#ISCELL
  standard offpage *
  page341_i149
#CELL
  pure_quanta q_cap *
  page341_i15
#CELL
  pure_quanta q_res *
  page341_i150
#ISCELL
  pure_quanta_power universal_gnd *
  page341_i151
#ISCELL
  standard offpage *
  page341_i152
#ISCELL
  standard offpage *
  page341_i153
#ISCELL
  standard offpage *
  page341_i154
#ISCELL
  standard offpage *
  page341_i155
#ISCELL
  standard offpage *
  page341_i156
#ISCELL
  standard offpage *
  page341_i157
#ISCELL
  standard offpage *
  page341_i158
#ISCELL
  standard offpage *
  page341_i159
#CELL
  pure_quanta q_cap *
  page341_i16
#ISCELL
  standard offpage *
  page341_i160
#ISCELL
  standard offpage *
  page341_i161
#ISCELL
  standard offpage *
  page341_i162
#ISCELL
  standard offpage *
  page341_i163
#ISCELL
  standard offpage *
  page341_i164
#ISCELL
  standard offpage *
  page341_i165
#ISCELL
  standard tap *
  page341_i166
#ISCELL
  standard tap *
  page341_i167
#CELL
  pure_quanta sconn168_me1016810202011 *
  page341_i168
#ISCELL
  pure_quanta_power universal_gnd *
  page341_i169
#CELL
  pure_quanta q_cap *
  page341_i17
#CELL
  pure_quanta q_res *
  page341_i170
#CELL
  pure_quanta q_res *
  page341_i171
#CELL
  pure_quanta q_cap *
  page341_i18
#ISCELL
  pure_quanta_power universal_gnd *
  page341_i19
#CELL
  pure_quanta q_res *
  page341_i2
#CELL
  pure_quanta q_cap *
  page341_i20
#CELL
  pure_quanta q_cap *
  page341_i21
#CELL
  pure_quanta q_cap *
  page341_i22
#CELL
  pure_quanta q_cap *
  page341_i23
#CELL
  pure_quanta q_cap *
  page341_i24
#ISCELL
  pure_quanta_power universal_gnd *
  page341_i25
#CELL
  pure_quanta q_res *
  page341_i26
#ISCELL
  pure_quanta_power universal_power *
  page341_i27
#CELL
  pure_quanta q_res *
  page341_i28
#ISCELL
  standard offpage *
  page341_i29
#CELL
  pure_quanta q_res *
  page341_i3
#ISCELL
  standard offpage *
  page341_i30
#ISCELL
  pure_quanta_power universal_gnd *
  page341_i31
#CELL
  pure_quanta q_res *
  page341_i32
#CELL
  pure_quanta q_res *
  page341_i33
#CELL
  pure_quanta q_res *
  page341_i34
#ISCELL
  standard offpage *
  page341_i35
#ISCELL
  standard offpage *
  page341_i36
#ISCELL
  standard offpage *
  page341_i37
#ISCELL
  standard offpage *
  page341_i38
#ISCELL
  standard offpage *
  page341_i39
#ISCELL
  pure_quanta_power universal_gnd *
  page341_i4
#ISCELL
  standard offpage *
  page341_i40
#ISCELL
  standard offpage *
  page341_i41
#CELL
  pure_quanta q_res *
  page341_i42
#CELL
  pure_quanta q_res *
  page341_i43
#CELL
  pure_quanta q_res *
  page341_i44
#CELL
  pure_quanta q_res *
  page341_i45
#ISCELL
  standard offpage *
  page341_i46
#ISCELL
  standard tap *
  page341_i47
#ISCELL
  standard tap *
  page341_i48
#ISCELL
  pure_quanta_power universal_gnd *
  page341_i49
#ISCELL
  standard offpage *
  page341_i5
#ISCELL
  standard tap *
  page341_i50
#ISCELL
  standard tap *
  page341_i51
#ISCELL
  standard tap *
  page341_i52
#ISCELL
  standard tap *
  page341_i53
#ISCELL
  standard tap *
  page341_i54
#ISCELL
  standard tap *
  page341_i55
#ISCELL
  standard tap *
  page341_i56
#ISCELL
  standard tap *
  page341_i57
#ISCELL
  standard tap *
  page341_i58
#ISCELL
  standard tap *
  page341_i59
#ISCELL
  standard offpage *
  page341_i6
#ISCELL
  standard tap *
  page341_i60
#ISCELL
  standard tap *
  page341_i61
#ISCELL
  standard offpage *
  page341_i62
#ISCELL
  standard offpage *
  page341_i63
#ISCELL
  standard offpage *
  page341_i64
#ISCELL
  standard offpage *
  page341_i65
#ISCELL
  standard offpage *
  page341_i66
#ISCELL
  standard offpage *
  page341_i67
#ISCELL
  standard tap *
  page341_i68
#ISCELL
  standard tap *
  page341_i69
#ISCELL
  standard offpage *
  page341_i7
#ISCELL
  standard tap *
  page341_i70
#ISCELL
  standard tap *
  page341_i71
#ISCELL
  standard tap *
  page341_i72
#ISCELL
  standard tap *
  page341_i73
#ISCELL
  standard tap *
  page341_i74
#ISCELL
  standard tap *
  page341_i75
#ISCELL
  standard tap *
  page341_i76
#ISCELL
  standard tap *
  page341_i77
#ISCELL
  standard tap *
  page341_i78
#ISCELL
  standard tap *
  page341_i79
#ISCELL
  standard offpage *
  page341_i8
#ISCELL
  standard tap *
  page341_i80
#ISCELL
  standard tap *
  page341_i81
#ISCELL
  standard tap *
  page341_i82
#ISCELL
  standard tap *
  page341_i83
#ISCELL
  standard offpage *
  page341_i84
#ISCELL
  standard offpage *
  page341_i85
#CELL
  pure_quanta q_res *
  page341_i86
#ISCELL
  standard offpage *
  page341_i87
#ISCELL
  standard offpage *
  page341_i88
#ISCELL
  standard offpage *
  page341_i89
#CELL
  pure_quanta q_res *
  page341_i9
#ISCELL
  standard offpage *
  page341_i90
#ISCELL
  standard offpage *
  page341_i91
#ISCELL
  standard offpage *
  page341_i92
#ISCELL
  standard offpage *
  page341_i93
#ISCELL
  standard offpage *
  page341_i94
#ISCELL
  standard offpage *
  page341_i95
#ISCELL
  standard offpage *
  page341_i96
#ISCELL
  pure_quanta_power universal_power *
  page341_i97
#ISCELL
  pure_quanta_power universal_power *
  page341_i98
#ISCELL
  pure_quanta_power universal_power *
  page341_i99
